# T6G (Grand Teton) — schematic netlist excerpt (pin names and nets, part order shuffled) for the footprints in the layout excerpt that follows; sources: Cadence DE-HDL packaged netlist, KiCad conversion of 04192023_DAF0TMB3IC0_F0TG_MB_C_brd_V02_OCP.brd

R205  Q_RES  0 5% CHIP  pkg 0402LF  page 82 : A = CPU1_XTRIG_L5 ; B = FM_CPU1_XTRIG_L5
C1031  Q_CAP  1UF 4V 20% X6S  pkg 0201  page 312 : A = P0V9_CPU0_RT3_2A ; B = GND
PC6566_1  Q_CAP  22UF 4V 20% X6S  pkg C0805  page 363 : A = P0V9_CPU0_RT_2D ; B = GND
PC484_2  Q_CAP  22UF 16V 20% X6S  pkg C0805  page 194 : A = SW_P12V_AUX_PVDDCR_CPU0_P0_FLT ; B = GND

(kicad_pcb
	(version 20260206)
	(generator "pcbnew")
	(generator_version "10.0")
	(general
		(thickness 1.6)
		(legacy_teardrops no)
	)
	(paper "A4")
	(title_block
		(title "04192023_DAF0TMB3IC0_F0TG_MB_C_brd_V02_OCP.brd")
		(comment 1 "Grand Teton / footprints 8202-8205 of 8354")
	)
	(layers
		(0 "F.Cu" signal "TOP")
		(4 "In1.Cu" signal "GND")
		(6 "In2.Cu" signal "IN1")
		(8 "In3.Cu" signal "GND1")
		(10 "In4.Cu" signal "IN2")
		(12 "In5.Cu" signal "GND2")
		(14 "In6.Cu" signal "IN3")
		(16 "In7.Cu" signal "GND3")
		(18 "In8.Cu" signal "VCC")
		(20 "In9.Cu" signal "VCC1")
		(22 "In10.Cu" signal "GND4")
		(24 "In11.Cu" signal "IN4")
		(26 "In12.Cu" signal "GND5")
		(28 "In13.Cu" signal "IN5")
		(30 "In14.Cu" signal "GND6")
		(32 "In15.Cu" signal "IN6")
		(34 "In16.Cu" signal "GND7")
		(2 "B.Cu" signal "BOTTOM")
		(9 "F.Adhes" user "F.Adhesive")
		(11 "B.Adhes" user "B.Adhesive")
		(13 "F.Paste" user "Package Geometry/Pastemask Top")
		(15 "B.Paste" user "Package Geometry/Pastemask Bottom")
		(5 "F.SilkS" user "Ref Des/Silkscreen Top")
		(7 "B.SilkS" user "Ref Des/Silkscreen Bottom")
		(1 "F.Mask" user "Board Geometry/Soldermask Top")
		(3 "B.Mask" user "Board Geometry/Soldermask Bottom")
		(17 "Dwgs.User" user "User.Drawings")
		(19 "Cmts.User" user "User.Comments")
		(21 "Eco1.User" user "User.Eco1")
		(23 "Eco2.User" user "User.Eco2")
		(25 "Edge.Cuts" user "Board Geometry/Outline")
		(27 "Margin" user)
		(31 "F.CrtYd" user "Package Geometry/Place Bound Top")
		(29 "B.CrtYd" user "Package Geometry/Place Bound Bottom")
		(35 "F.Fab" user "Ref Des/Assembly Top")
		(33 "B.Fab" user "Ref Des/Assembly Bottom")
	)
	(footprint ""
		(layer "B.Cu")
		(at 171.199048 -105.121202 180)
		(property "Reference" "R205"
			(at 0 0 0)
			(layer "B.SilkS")
			(hide yes)
			(effects
				(font
					(size 1.27 1.27)
				)
				(justify mirror)
			)
		)
		(property "Value" ""
			(at 0 0 0)
			(layer "B.Fab")
			(effects
				(font
					(size 1.27 1.27)
				)
				(justify mirror)
			)
		)
		(duplicate_pad_numbers_are_jumpers no)
		(fp_line
			(start 0.7874 0.4064)
			(end 0.7874 -0.4064)
			(stroke
				(width 0.1524)
				(type default)
			)
			(layer "B.SilkS")
		)
		(fp_line
			(start 0.7874 -0.4064)
			(end -0.7874 -0.4064)
			(stroke
				(width 0.1524)
				(type default)
			)
			(layer "B.SilkS")
		)
		(fp_line
			(start -0.7874 0.4064)
			(end 0.7874 0.4064)
			(stroke
				(width 0.1524)
				(type default)
			)
			(layer "B.SilkS")
		)
		(fp_line
			(start -0.7874 -0.4064)
			(end -0.7874 0.4064)
			(stroke
				(width 0.1524)
				(type default)
			)
			(layer "B.SilkS")
		)
		(fp_line
			(start 0.67945 0.3048)
			(end 0.67945 -0.305054)
			(stroke
				(width 0.1)
				(type default)
			)
			(layer "B.Fab")
		)
		(fp_line
			(start 0.67945 -0.305054)
			(end 0.12065 -0.305054)
			(stroke
				(width 0.1)
				(type default)
			)
			(layer "B.Fab")
		)
		(fp_line
			(start 0.12065 0.3048)
			(end 0.67945 0.3048)
			(stroke
				(width 0.1)
				(type default)
			)
			(layer "B.Fab")
		)
		(fp_line
			(start 0.12065 0.2794)
			(end 0.12065 0.3048)
			(stroke
				(width 0.1)
				(type default)
			)
			(layer "B.Fab")
		)
		(fp_line
			(start 0.12065 -0.2794)
			(end -0.12065 -0.2794)
			(stroke
				(width 0.1)
				(type default)
			)
			(layer "B.Fab")
		)
		(fp_line
			(start 0.12065 -0.305054)
			(end 0.12065 -0.2794)
			(stroke
				(width 0.1)
				(type default)
			)
			(layer "B.Fab")
		)
		(fp_line
			(start -0.120396 0.3048)
			(end -0.120396 0.2794)
			(stroke
				(width 0.1)
				(type default)
			)
			(layer "B.Fab")
		)
		(fp_line
			(start -0.120396 0.2794)
			(end 0.12065 0.2794)
			(stroke
				(width 0.1)
				(type default)
			)
			(layer "B.Fab")
		)
		(fp_line
			(start -0.12065 -0.2794)
			(end -0.12065 -0.3048)
			(stroke
				(width 0.1)
				(type default)
			)
			(layer "B.Fab")
		)
		(fp_line
			(start -0.12065 -0.3048)
			(end -0.67945 -0.3048)
			(stroke
				(width 0.1)
				(type default)
			)
			(layer "B.Fab")
		)
		(fp_line
			(start -0.67945 0.3048)
			(end -0.120396 0.3048)
			(stroke
				(width 0.1)
				(type default)
			)
			(layer "B.Fab")
		)
		(fp_line
			(start -0.67945 -0.3048)
			(end -0.67945 0.3048)
			(stroke
				(width 0.1)
				(type default)
			)
			(layer "B.Fab")
		)
		(pad "1" smd circle
			(at 0.40005 0)
			(size 0 0)
			(layers "B.Cu" "B.Mask" "B.Paste")
			(net "CPU1_XTRIG_L5")
		)
		(pad "2" smd circle
			(at -0.40005 0)
			(size 0 0)
			(layers "B.Cu" "B.Mask" "B.Paste")
			(net "FM_CPU1_XTRIG_L5")
		)
	)
	(footprint ""
		(layer "B.Cu")
		(at 459.339188 -389.132064 -90)
		(property "Reference" "PC6566_1"
			(at 0 0 90)
			(layer "B.SilkS")
			(hide yes)
			(effects
				(font
					(size 1.27 1.27)
				)
				(justify mirror)
			)
		)
		(property "Value" ""
			(at 0 0 90)
			(layer "B.Fab")
			(effects
				(font
					(size 1.27 1.27)
				)
				(justify mirror)
			)
		)
		(duplicate_pad_numbers_are_jumpers no)
		(fp_line
			(start -1.524 0.762)
			(end 1.524 0.762)
			(stroke
				(width 0.1524)
				(type default)
			)
			(layer "B.SilkS")
		)
		(fp_line
			(start 1.524 0.762)
			(end 1.524 -0.762)
			(stroke
				(width 0.1524)
				(type default)
			)
			(layer "B.SilkS")
		)
		(fp_line
			(start -1.524 -0.762)
			(end -1.524 0.762)
			(stroke
				(width 0.1524)
				(type default)
			)
			(layer "B.SilkS")
		)
		(fp_line
			(start 1.524 -0.762)
			(end -1.524 -0.762)
			(stroke
				(width 0.1524)
				(type default)
			)
			(layer "B.SilkS")
		)
		(fp_line
			(start -1.1049 0.724916)
			(end -1.1049 -0.724916)
			(stroke
				(width 0.1)
				(type default)
			)
			(layer "B.Fab")
		)
		(fp_line
			(start 1.1049 0.724916)
			(end -1.1049 0.724916)
			(stroke
				(width 0.1)
				(type default)
			)
			(layer "B.Fab")
		)
		(fp_line
			(start -1.1049 -0.724916)
			(end 1.1049 -0.724916)
			(stroke
				(width 0.1)
				(type default)
			)
			(layer "B.Fab")
		)
		(fp_line
			(start 1.1049 -0.724916)
			(end 1.1049 0.724916)
			(stroke
				(width 0.1)
				(type default)
			)
			(layer "B.Fab")
		)
		(pad "1" smd rect
			(at 0.889 0 270)
			(size 1.016 1.27)
			(layers "B.Cu" "B.Mask" "B.Paste")
			(net "P0V9_CPU0_RT_2D")
		)
		(pad "2" smd rect
			(at -0.889 0 270)
			(size 1.016 1.27)
			(layers "B.Cu" "B.Mask" "B.Paste")
			(net "GND")
		)
	)
	(footprint ""
		(layer "B.Cu")
		(at 371.650006 -178.994816 90)
		(property "Reference" "PC484_2"
			(at 0 0 90)
			(layer "B.SilkS")
			(hide yes)
			(effects
				(font
					(size 1.27 1.27)
				)
				(justify mirror)
			)
		)
		(property "Value" ""
			(at 0 0 90)
			(layer "B.Fab")
			(effects
				(font
					(size 1.27 1.27)
				)
				(justify mirror)
			)
		)
		(duplicate_pad_numbers_are_jumpers no)
		(fp_line
			(start 1.524 -0.762)
			(end -1.524 -0.762)
			(stroke
				(width 0.1524)
				(type default)
			)
			(layer "B.SilkS")
		)
		(fp_line
			(start -1.524 -0.762)
			(end -1.524 0.762)
			(stroke
				(width 0.1524)
				(type default)
			)
			(layer "B.SilkS")
		)
		(fp_line
			(start 1.524 0.762)
			(end 1.524 -0.762)
			(stroke
				(width 0.1524)
				(type default)
			)
			(layer "B.SilkS")
		)
		(fp_line
			(start -1.524 0.762)
			(end 1.524 0.762)
			(stroke
				(width 0.1524)
				(type default)
			)
			(layer "B.SilkS")
		)
		(fp_line
			(start 1.1049 -0.724916)
			(end 1.1049 0.724916)
			(stroke
				(width 0.1)
				(type default)
			)
			(layer "B.Fab")
		)
		(fp_line
			(start -1.1049 -0.724916)
			(end 1.1049 -0.724916)
			(stroke
				(width 0.1)
				(type default)
			)
			(layer "B.Fab")
		)
		(fp_line
			(start 1.1049 0.724916)
			(end -1.1049 0.724916)
			(stroke
				(width 0.1)
				(type default)
			)
			(layer "B.Fab")
		)
		(fp_line
			(start -1.1049 0.724916)
			(end -1.1049 -0.724916)
			(stroke
				(width 0.1)
				(type default)
			)
			(layer "B.Fab")
		)
		(pad "1" smd rect
			(at 0.889 0 90)
			(size 1.016 1.27)
			(layers "B.Cu" "B.Mask" "B.Paste")
			(net "SW_P12V_AUX_PVDDCR_CPU0_P0_FLT")
		)
		(pad "2" smd rect
			(at -0.889 0 90)
			(size 1.016 1.27)
			(layers "B.Cu" "B.Mask" "B.Paste")
			(net "GND")
		)
	)
	(footprint ""
		(layer "B.Cu")
		(at 371.678454 -395.148562 90)
		(property "Reference" "C1031"
			(at 0 0 90)
			(layer "B.SilkS")
			(hide yes)
			(effects
				(font
					(size 1.27 1.27)
				)
				(justify mirror)
			)
		)
		(property "Value" ""
			(at 0 0 90)
			(layer "B.Fab")
			(effects
				(font
					(size 1.27 1.27)
				)
				(justify mirror)
			)
		)
		(duplicate_pad_numbers_are_jumpers no)
		(fp_line
			(start 0.299974 -0.150114)
			(end -0.299974 -0.150114)
			(stroke
				(width 0.1)
				(type default)
			)
			(layer "B.Fab")
		)
		(fp_line
			(start -0.299974 -0.150114)
			(end -0.299974 0.150114)
			(stroke
				(width 0.1)
				(type default)
			)
			(layer "B.Fab")
		)
		(fp_line
			(start 0.299974 0.150114)
			(end 0.299974 -0.150114)
			(stroke
				(width 0.1)
				(type default)
			)
			(layer "B.Fab")
		)
		(fp_line
			(start -0.299974 0.150114)
			(end 0.299974 0.150114)
			(stroke
				(width 0.1)
				(type default)
			)
			(layer "B.Fab")
		)
		(pad "1" smd rect
			(at 0.2667 0 270)
			(size 0.3048 0.381)
			(layers "B.Cu" "B.Mask" "B.Paste")
			(net "P0V9_CPU0_RT3_2A")
		)
		(pad "2" smd rect
			(at -0.2667 0 270)
			(size 0.3048 0.381)
			(layers "B.Cu" "B.Mask" "B.Paste")
			(net "GND")
		)
	)
)
